(kicad_pcb
	(version 20241229)
	(generator "pcbnew")
	(generator_version "9.0")
	(general
		(thickness 1.599998)
		(legacy_teardrops no)
	)
	(paper "A4")
	(title_block
		(title "Artix - Datacenter Secure Control Module (DC-SCM)")
		(date "2024-11-06")
		(rev "1.1.3")
		(comment 9 "footprints 175-179 of 544")
	)
	(layers
		(0 "F.Cu" signal)
		(4 "In1.Cu" signal)
		(6 "In2.Cu" signal)
		(8 "In3.Cu" signal)
		(10 "In4.Cu" signal)
		(12 "In5.Cu" signal)
		(14 "In6.Cu" signal)
		(2 "B.Cu" signal)
		(9 "F.Adhes" user "F.Adhesive")
		(11 "B.Adhes" user "B.Adhesive")
		(13 "F.Paste" user)
		(15 "B.Paste" user)
		(5 "F.SilkS" user "F.Silkscreen")
		(7 "B.SilkS" user "B.Silkscreen")
		(1 "F.Mask" user)
		(3 "B.Mask" user)
		(17 "Dwgs.User" user "User.Drawings")
		(19 "Cmts.User" user "User.Comments")
		(21 "Eco1.User" user "User.Eco1")
		(23 "Eco2.User" user "User.Eco2")
		(25 "Edge.Cuts" user)
		(27 "Margin" user)
		(31 "F.CrtYd" user "F.Courtyard")
		(29 "B.CrtYd" user "B.Courtyard")
		(35 "F.Fab" user)
		(33 "B.Fab" user)
	)
	(footprint "antmicro-footprints:C_0603_1608Metric"
		(layer "F.Cu")
		(at 81.115 68.8 -90)
		(descr "Capacitor SMD 0603")
		(tags "capacitor 0603")
		(property "Reference" "C73"
			(at -1.625 16.804 90)
			(layer "F.SilkS")
			(effects
				(font
					(size 0.7 0.7)
					(thickness 0.15)
				)
				(justify right bottom)
			)
		)
		(property "Value" "C_47u_0603"
			(at 0 1.6 90)
			(layer "F.Fab")
			(effects
				(font
					(size 0.7 0.7)
					(thickness 0.15)
				)
				(justify right bottom)
			)
		)
		(property "Datasheet" "https://www.murata.com/products/productdetail?partno=GRM188R60J476ME15%23"
			(at 0 0 270)
			(layer "F.Fab")
			(hide yes)
			(effects
				(font
					(size 1.27 1.27)
					(thickness 0.15)
				)
			)
		)
		(property "Description" "SMD Multilayer Ceramic Capacitor, 47 µF, 6.3 V, 0603 [1608 Metric], ± 20%, X5R, GRM Series"
			(at 0 0 270)
			(layer "F.Fab")
			(hide yes)
			(effects
				(font
					(size 1.27 1.27)
					(thickness 0.15)
				)
			)
		)
		(property "Author" "Antmicro"
			(at 12.315 149.915 0)
			(layer "F.Fab")
			(hide yes)
			(effects
				(font
					(size 1 1)
					(thickness 0.15)
				)
			)
		)
		(property "Dielectric" ""
			(at 12.315 149.915 0)
			(layer "F.Fab")
			(hide yes)
			(effects
				(font
					(size 1 1)
					(thickness 0.15)
				)
			)
		)
		(property "License" "Apache-2.0"
			(at 12.315 149.915 0)
			(layer "F.Fab")
			(hide yes)
			(effects
				(font
					(size 1 1)
					(thickness 0.15)
				)
			)
		)
		(property "MPN" "GRM188R60J476ME15D"
			(at 12.315 149.915 0)
			(layer "F.Fab")
			(hide yes)
			(effects
				(font
					(size 1 1)
					(thickness 0.15)
				)
			)
		)
		(property "Manufacturer" "Murata"
			(at 12.315 149.915 0)
			(layer "F.Fab")
			(hide yes)
			(effects
				(font
					(size 1 1)
					(thickness 0.15)
				)
			)
		)
		(property "Val" "47u"
			(at 12.315 149.915 0)
			(layer "F.Fab")
			(hide yes)
			(effects
				(font
					(size 1 1)
					(thickness 0.15)
				)
			)
		)
		(property "Voltage" ""
			(at 12.315 149.915 0)
			(layer "F.Fab")
			(hide yes)
			(effects
				(font
					(size 1 1)
					(thickness 0.15)
				)
			)
		)
		(sheetname "/Power supply/")
		(sheetfile "power-supply.kicad_sch")
		(attr smd)
		(fp_line
			(start -0.15 0.4)
			(end 0.15 0.4)
			(stroke
				(width 0.15)
				(type solid)
			)
			(layer "F.SilkS")
		)
		(fp_line
			(start -0.15 -0.4)
			(end 0.15 -0.4)
			(stroke
				(width 0.15)
				(type solid)
			)
			(layer "F.SilkS")
		)
		(fp_rect
			(start -1.25 -0.65)
			(end 1.25 0.65)
			(stroke
				(width 0.05)
				(type solid)
			)
			(fill no)
			(layer "F.CrtYd")
		)
		(fp_rect
			(start -0.8 -0.4)
			(end 0.8 0.4)
			(stroke
				(width 0.15)
				(type solid)
			)
			(fill no)
			(layer "F.Fab")
		)
		(pad "1" smd roundrect
			(at -0.7 0 270)
			(size 0.8 1)
			(layers "F.Cu" "F.Mask" "F.Paste")
			(roundrect_rratio 0.2)
			(net 1 "GND")
			(pintype "passive")
		)
		(pad "2" smd roundrect
			(at 0.7 0 270)
			(size 0.8 1)
			(layers "F.Cu" "F.Mask" "F.Paste")
			(roundrect_rratio 0.2)
			(net 114 "Net-(C72-Pad2)")
			(pintype "passive")
		)
	)
	(footprint "antmicro-footprints:C_0603_1608Metric"
		(layer "F.Cu")
		(at 79.64 68.8 -90)
		(descr "Capacitor SMD 0603")
		(tags "capacitor 0603")
		(property "Reference" "C72"
			(at -1.625 16.44 90)
			(layer "F.SilkS")
			(effects
				(font
					(size 0.7 0.7)
					(thickness 0.15)
				)
				(justify right bottom)
			)
		)
		(property "Value" "C_47u_0603"
			(at 0 1.6 90)
			(layer "F.Fab")
			(effects
				(font
					(size 0.7 0.7)
					(thickness 0.15)
				)
				(justify right bottom)
			)
		)
		(property "Datasheet" "https://www.murata.com/products/productdetail?partno=GRM188R60J476ME15%23"
			(at 0 0 270)
			(layer "F.Fab")
			(hide yes)
			(effects
				(font
					(size 1.27 1.27)
					(thickness 0.15)
				)
			)
		)
		(property "Description" "SMD Multilayer Ceramic Capacitor, 47 µF, 6.3 V, 0603 [1608 Metric], ± 20%, X5R, GRM Series"
			(at 0 0 270)
			(layer "F.Fab")
			(hide yes)
			(effects
				(font
					(size 1.27 1.27)
					(thickness 0.15)
				)
			)
		)
		(property "Author" "Antmicro"
			(at 10.84 148.44 0)
			(layer "F.Fab")
			(hide yes)
			(effects
				(font
					(size 1 1)
					(thickness 0.15)
				)
			)
		)
		(property "Dielectric" ""
			(at 10.84 148.44 0)
			(layer "F.Fab")
			(hide yes)
			(effects
				(font
					(size 1 1)
					(thickness 0.15)
				)
			)
		)
		(property "License" "Apache-2.0"
			(at 10.84 148.44 0)
			(layer "F.Fab")
			(hide yes)
			(effects
				(font
					(size 1 1)
					(thickness 0.15)
				)
			)
		)
		(property "MPN" "GRM188R60J476ME15D"
			(at 10.84 148.44 0)
			(layer "F.Fab")
			(hide yes)
			(effects
				(font
					(size 1 1)
					(thickness 0.15)
				)
			)
		)
		(property "Manufacturer" "Murata"
			(at 10.84 148.44 0)
			(layer "F.Fab")
			(hide yes)
			(effects
				(font
					(size 1 1)
					(thickness 0.15)
				)
			)
		)
		(property "Val" "47u"
			(at 10.84 148.44 0)
			(layer "F.Fab")
			(hide yes)
			(effects
				(font
					(size 1 1)
					(thickness 0.15)
				)
			)
		)
		(property "Voltage" ""
			(at 10.84 148.44 0)
			(layer "F.Fab")
			(hide yes)
			(effects
				(font
					(size 1 1)
					(thickness 0.15)
				)
			)
		)
		(sheetname "/Power supply/")
		(sheetfile "power-supply.kicad_sch")
		(attr smd)
		(fp_line
			(start -0.15 0.4)
			(end 0.15 0.4)
			(stroke
				(width 0.15)
				(type solid)
			)
			(layer "F.SilkS")
		)
		(fp_line
			(start -0.15 -0.4)
			(end 0.15 -0.4)
			(stroke
				(width 0.15)
				(type solid)
			)
			(layer "F.SilkS")
		)
		(fp_rect
			(start -1.25 -0.65)
			(end 1.25 0.65)
			(stroke
				(width 0.05)
				(type solid)
			)
			(fill no)
			(layer "F.CrtYd")
		)
		(fp_rect
			(start -0.8 -0.4)
			(end 0.8 0.4)
			(stroke
				(width 0.15)
				(type solid)
			)
			(fill no)
			(layer "F.Fab")
		)
		(pad "1" smd roundrect
			(at -0.7 0 270)
			(size 0.8 1)
			(layers "F.Cu" "F.Mask" "F.Paste")
			(roundrect_rratio 0.2)
			(net 1 "GND")
			(pintype "passive")
		)
		(pad "2" smd roundrect
			(at 0.7 0 270)
			(size 0.8 1)
			(layers "F.Cu" "F.Mask" "F.Paste")
			(roundrect_rratio 0.2)
			(net 114 "Net-(C72-Pad2)")
			(pintype "passive")
		)
	)
	(footprint "antmicro-footprints:L_WE-PDF-1064"
		(layer "F.Cu")
		(at 71 71.705)
		(property "Reference" "L1"
			(at -3.78 -5.475 180)
			(layer "F.SilkS")
			(effects
				(font
					(size 0.7 0.7)
					(thickness 0.15)
				)
				(justify left bottom)
			)
		)
		(property "Value" "L_7u2_7.9A_WE-PDF-1064"
			(at -5.6 6.6 180)
			(layer "F.Fab")
			(effects
				(font
					(size 0.7 0.7)
					(thickness 0.15)
				)
				(justify left bottom)
			)
		)
		(property "Datasheet" "https://www.we-online.com/catalog/datasheet/7447798720.pdf"
			(at 0 0 0)
			(layer "F.Fab")
			(hide yes)
			(effects
				(font
					(size 1.27 1.27)
					(thickness 0.15)
				)
			)
		)
		(property "Description" "Power Inductor (SMD), 7.2 µH, 7.9 A, Shielded, 6 A, WE-PDF"
			(at 0 0 0)
			(layer "F.Fab")
			(hide yes)
			(effects
				(font
					(size 1.27 1.27)
					(thickness 0.15)
				)
			)
		)
		(property "Author" "Antmicro"
			(at 0 0 0)
			(layer "F.Fab")
			(hide yes)
			(effects
				(font
					(size 1 1)
					(thickness 0.15)
				)
			)
		)
		(property "IMax" "7.9 A"
			(at 0 0 0)
			(layer "F.Fab")
			(hide yes)
			(effects
				(font
					(size 1 1)
					(thickness 0.15)
				)
			)
		)
		(property "ISat" "6 A"
			(at 0 0 0)
			(layer "F.Fab")
			(hide yes)
			(effects
				(font
					(size 1 1)
					(thickness 0.15)
				)
			)
		)
		(property "License" "Apache-2.0"
			(at 0 0 0)
			(layer "F.Fab")
			(hide yes)
			(effects
				(font
					(size 1 1)
					(thickness 0.15)
				)
			)
		)
		(property "MPN" "7447798720"
			(at 0 0 0)
			(layer "F.Fab")
			(hide yes)
			(effects
				(font
					(size 1 1)
					(thickness 0.15)
				)
			)
		)
		(property "Manufacturer" "Würth Elektronik"
			(at 0 0 0)
			(layer "F.Fab")
			(hide yes)
			(effects
				(font
					(size 1 1)
					(thickness 0.15)
				)
			)
		)
		(property "Size" "10.2x10.2"
			(at 0 0 0)
			(layer "F.Fab")
			(hide yes)
			(effects
				(font
					(size 1 1)
					(thickness 0.15)
				)
			)
		)
		(property "Val" "7u2/7.9A"
			(at 0 0 0)
			(layer "F.Fab")
			(hide yes)
			(effects
				(font
					(size 1 1)
					(thickness 0.15)
				)
			)
		)
		(sheetname "/Power supply/")
		(sheetfile "power-supply.kicad_sch")
		(attr smd)
		(fp_line
			(start -5.225 -5.225)
			(end 4.125 -5.225)
			(stroke
				(width 0.15)
				(type solid)
			)
			(layer "F.SilkS")
		)
		(fp_line
			(start -5.225 -1.925)
			(end -5.225 -5.225)
			(stroke
				(width 0.15)
				(type solid)
			)
			(layer "F.SilkS")
		)
		(fp_line
			(start -5.225 5.225)
			(end -5.225 1.925)
			(stroke
				(width 0.15)
				(type solid)
			)
			(layer "F.SilkS")
		)
		(fp_line
			(start 4.125 -5.225)
			(end 5.225 -4.125)
			(stroke
				(width 0.15)
				(type solid)
			)
			(layer "F.SilkS")
		)
		(fp_line
			(start 5.225 -4.125)
			(end 5.225 -1.925)
			(stroke
				(width 0.15)
				(type solid)
			)
			(layer "F.SilkS")
		)
		(fp_line
			(start 5.225 1.925)
			(end 5.225 5.225)
			(stroke
				(width 0.15)
				(type solid)
			)
			(layer "F.SilkS")
		)
		(fp_line
			(start 5.225 5.225)
			(end -5.225 5.225)
			(stroke
				(width 0.15)
				(type solid)
			)
			(layer "F.SilkS")
		)
		(fp_line
			(start -5.55 -1.95)
			(end -5.55 1.95)
			(stroke
				(width 0.05)
				(type solid)
			)
			(layer "F.CrtYd")
		)
		(fp_line
			(start -5.55 1.95)
			(end -5.35 1.95)
			(stroke
				(width 0.05)
				(type solid)
			)
			(layer "F.CrtYd")
		)
		(fp_line
			(start -5.35 -5.35)
			(end -5.35 -1.95)
			(stroke
				(width 0.05)
				(type solid)
			)
			(layer "F.CrtYd")
		)
		(fp_line
			(start -5.35 -1.95)
			(end -5.55 -1.95)
			(stroke
				(width 0.05)
				(type solid)
			)
			(layer "F.CrtYd")
		)
		(fp_line
			(start -5.35 1.95)
			(end -5.35 5.35)
			(stroke
				(width 0.05)
				(type solid)
			)
			(layer "F.CrtYd")
		)
		(fp_line
			(start -5.35 5.35)
			(end 5.35 5.35)
			(stroke
				(width 0.05)
				(type solid)
			)
			(layer "F.CrtYd")
		)
		(fp_line
			(start 5.35 -5.35)
			(end -5.35 -5.35)
			(stroke
				(width 0.05)
				(type solid)
			)
			(layer "F.CrtYd")
		)
		(fp_line
			(start 5.35 -1.95)
			(end 5.35 -5.35)
			(stroke
				(width 0.05)
				(type solid)
			)
			(layer "F.CrtYd")
		)
		(fp_line
			(start 5.35 1.95)
			(end 5.55 1.95)
			(stroke
				(width 0.05)
				(type solid)
			)
			(layer "F.CrtYd")
		)
		(fp_line
			(start 5.35 5.35)
			(end 5.35 1.95)
			(stroke
				(width 0.05)
				(type solid)
			)
			(layer "F.CrtYd")
		)
		(fp_line
			(start 5.55 -1.95)
			(end 5.35 -1.95)
			(stroke
				(width 0.05)
				(type solid)
			)
			(layer "F.CrtYd")
		)
		(fp_line
			(start 5.55 -1.95)
			(end 5.55 1.95)
			(stroke
				(width 0.05)
				(type solid)
			)
			(layer "F.CrtYd")
		)
		(fp_rect
			(start -5.101 -5.101)
			(end 5.099 5.099)
			(stroke
				(width 0.15)
				(type solid)
			)
			(fill no)
			(layer "F.Fab")
		)
		(pad "1" smd roundrect
			(at -4.1 0 90)
			(size 3.4 2.4)
			(layers "F.Cu" "F.Mask" "F.Paste")
			(roundrect_rratio 0.1)
			(net 8 "Net-(D3-C)")
			(pintype "passive")
		)
		(pad "2" smd roundrect
			(at 4.1 0 90)
			(size 3.4 2.4)
			(layers "F.Cu" "F.Mask" "F.Paste")
			(roundrect_rratio 0.1)
			(net 114 "Net-(C72-Pad2)")
			(pintype "passive")
		)
	)
	(footprint "antmicro-footprints:R_1206_3216Metric"
		(layer "F.Cu")
		(at 79 76.3 180)
		(property "Reference" "R69"
			(at -0.2 1.105 0)
			(layer "F.SilkS")
			(effects
				(font
					(size 0.7 0.7)
					(thickness 0.15)
				)
				(justify right bottom)
			)
		)
		(property "Value" "R_0R_1206"
			(at 0 2 0)
			(layer "F.Fab")
			(effects
				(font
					(size 0.7 0.7)
					(thickness 0.15)
				)
				(justify right bottom)
			)
		)
		(property "Datasheet" "https://www.farnell.com/datasheets/2860635.pdf"
			(at 0 0 180)
			(layer "F.Fab")
			(hide yes)
			(effects
				(font
					(size 1.27 1.27)
					(thickness 0.15)
				)
			)
		)
		(property "Description" "Zero Ohm Resistor, Jumper, 1206 [3216 Metric], Thick Film, 250 mW, 2 A, Surface Mount Device"
			(at 0 0 180)
			(layer "F.Fab")
			(hide yes)
			(effects
				(font
					(size 1.27 1.27)
					(thickness 0.15)
				)
			)
		)
		(property "Author" "Antmicro"
			(at 158 152.6 0)
			(layer "F.Fab")
			(hide yes)
			(effects
				(font
					(size 1 1)
					(thickness 0.15)
				)
			)
		)
		(property "Current" "2A"
			(at 158 152.6 0)
			(layer "F.Fab")
			(hide yes)
			(effects
				(font
					(size 1 1)
					(thickness 0.15)
				)
			)
		)
		(property "License" "Apache-2.0"
			(at 158 152.6 0)
			(layer "F.Fab")
			(hide yes)
			(effects
				(font
					(size 1 1)
					(thickness 0.15)
				)
			)
		)
		(property "MPN" "MCMR12X000_PTL"
			(at 158 152.6 0)
			(layer "F.Fab")
			(hide yes)
			(effects
				(font
					(size 1 1)
					(thickness 0.15)
				)
			)
		)
		(property "Manufacturer" "Multicomp Pro"
			(at 158 152.6 0)
			(layer "F.Fab")
			(hide yes)
			(effects
				(font
					(size 1 1)
					(thickness 0.15)
				)
			)
		)
		(property "Tolerance" "~"
			(at 158 152.6 0)
			(layer "F.Fab")
			(hide yes)
			(effects
				(font
					(size 1 1)
					(thickness 0.15)
				)
			)
		)
		(property "Val" "0R"
			(at 158 152.6 0)
			(layer "F.Fab")
			(hide yes)
			(effects
				(font
					(size 1 1)
					(thickness 0.15)
				)
			)
		)
		(sheetname "/Power supply/")
		(sheetfile "power-supply.kicad_sch")
		(attr smd)
		(fp_line
			(start 0.8 0.901)
			(end -0.8 0.901)
			(stroke
				(width 0.15)
				(type solid)
			)
			(layer "F.SilkS")
		)
		(fp_line
			(start 0.8 -0.899)
			(end -0.8 -0.899)
			(stroke
				(width 0.15)
				(type solid)
			)
			(layer "F.SilkS")
		)
		(fp_rect
			(start -2.325 -1.15)
			(end 2.325 1.15)
			(stroke
				(width 0.05)
				(type default)
			)
			(fill no)
			(layer "F.CrtYd")
		)
		(fp_line
			(start 1.6 -0.802)
			(end 1.6 0.8)
			(stroke
				(width 0.15)
				(type solid)
			)
			(layer "F.Fab")
		)
		(fp_line
			(start -1.601 0.8)
			(end 1.6 0.8)
			(stroke
				(width 0.15)
				(type solid)
			)
			(layer "F.Fab")
		)
		(fp_line
			(start -1.601 -0.802)
			(end 1.6 -0.802)
			(stroke
				(width 0.15)
				(type solid)
			)
			(layer "F.Fab")
		)
		(fp_line
			(start -1.601 -0.802)
			(end -1.601 0.8)
			(stroke
				(width 0.15)
				(type solid)
			)
			(layer "F.Fab")
		)
		(pad "1" smd roundrect
			(at -1.5 0.001 180)
			(size 1.15 1.8)
			(layers "F.Cu" "F.Mask" "F.Paste")
			(roundrect_rratio 0.25)
			(net 4 "VCC5V0")
			(pintype "passive")
		)
		(pad "2" smd roundrect
			(at 1.5 0.001 180)
			(size 1.15 1.8)
			(layers "F.Cu" "F.Mask" "F.Paste")
			(roundrect_rratio 0.25)
			(net 114 "Net-(C72-Pad2)")
			(pintype "passive")
		)
	)
	(footprint "antmicro-footprints:C_0402_1005Metric"
		(layer "F.Cu")
		(at 75.065 168.715)
		(descr "Capacitor SMD 0402")
		(tags "capacitor SMD 0402")
		(property "Reference" "C17"
			(at 0.835 0.385 0)
			(layer "F.SilkS")
			(effects
				(font
					(size 0.7 0.7)
					(thickness 0.15)
				)
				(justify left bottom)
			)
		)
		(property "Value" "C_100n_6V3_0402"
			(at 0 1.4 0)
			(layer "F.Fab")
			(effects
				(font
					(size 0.7 0.7)
					(thickness 0.15)
				)
				(justify left bottom)
			)
		)
		(property "Datasheet" "https://www.passivecomponent.com/wp-content/uploads/datasheet/WTC_MLCC_General_Purpose.pdf"
			(at 0 0 0)
			(layer "F.Fab")
			(hide yes)
			(effects
				(font
					(size 1.27 1.27)
					(thickness 0.15)
				)
			)
		)
		(property "Description" "SMT Multilayer Ceramic Capacitor, 0.1 µF, 6.3 V, 0402 [1005 Metric], ± 10%, X5R, Walsin MLCC"
			(at 0 0 0)
			(layer "F.Fab")
			(hide yes)
			(effects
				(font
					(size 1.27 1.27)
					(thickness 0.15)
				)
			)
		)
		(property "Author" "Antmicro"
			(at 0 0 0)
			(layer "F.Fab")
			(hide yes)
			(effects
				(font
					(size 1 1)
					(thickness 0.15)
				)
			)
		)
		(property "Dielectric" ""
			(at 0 0 0)
			(layer "F.Fab")
			(hide yes)
			(effects
				(font
					(size 1 1)
					(thickness 0.15)
				)
			)
		)
		(property "License" "Apache-2.0"
			(at 0 0 0)
			(layer "F.Fab")
			(hide yes)
			(effects
				(font
					(size 1 1)
					(thickness 0.15)
				)
			)
		)
		(property "MPN" "0402X104K6R3CT"
			(at 0 0 0)
			(layer "F.Fab")
			(hide yes)
			(effects
				(font
					(size 1 1)
					(thickness 0.15)
				)
			)
		)
		(property "Manufacturer" "Walsin"
			(at 0 0 0)
			(layer "F.Fab")
			(hide yes)
			(effects
				(font
					(size 1 1)
					(thickness 0.15)
				)
			)
		)
		(property "Public" "False"
			(at 0 0 0)
			(layer "F.Fab")
			(hide yes)
			(effects
				(font
					(size 1 1)
					(thickness 0.15)
				)
			)
		)
		(property "Val" "100n"
			(at 0 0 0)
			(layer "F.Fab")
			(hide yes)
			(effects
				(font
					(size 1 1)
					(thickness 0.15)
				)
			)
		)
		(property "Voltage" ""
			(at 0 0 0)
			(layer "F.Fab")
			(hide yes)
			(effects
				(font
					(size 1 1)
					(thickness 0.15)
				)
			)
		)
		(sheetname "/Interfaces/")
		(sheetfile "interfaces.kicad_sch")
		(attr smd)
		(fp_rect
			(start -0.925 -0.47)
			(end 0.925 0.47)
			(stroke
				(width 0.05)
				(type default)
			)
			(fill no)
			(layer "F.CrtYd")
		)
		(fp_line
			(start -0.494 -0.25)
			(end 0.504 -0.25)
			(stroke
				(width 0.15)
				(type solid)
			)
			(layer "F.Fab")
		)
		(fp_line
			(start -0.494 0.248)
			(end -0.494 -0.25)
			(stroke
				(width 0.15)
				(type solid)
			)
			(layer "F.Fab")
		)
		(fp_line
			(start 0.504 -0.25)
			(end 0.504 0.248)
			(stroke
				(width 0.15)
				(type solid)
			)
			(layer "F.Fab")
		)
		(fp_line
			(start 0.504 0.248)
			(end -0.494 0.248)
			(stroke
				(width 0.15)
				(type solid)
			)
			(layer "F.Fab")
		)
		(pad "1" smd roundrect
			(at -0.48 0)
			(size 0.59 0.64)
			(layers "F.Cu" "F.Mask" "F.Paste")
			(roundrect_rratio 0.25)
			(net 1 "GND")
			(pintype "passive")
		)
		(pad "2" smd roundrect
			(at 0.48 0)
			(size 0.59 0.64)
			(layers "F.Cu" "F.Mask" "F.Paste")
			(roundrect_rratio 0.25)
			(net 6 "VCC1V0")
			(pintype "passive")
		)
	)
)
